(kicad_pcb
	(version 20241229)
	(generator "pcbnew")
	(generator_version "9.0")
	(general
		(thickness 1.711)
		(legacy_teardrops no)
	)
	(paper "A4")
	(title_block
		(title "Antmicro Baseboard for Jetson AGX Thor")
		(date "2026-02-18")
		(rev "1.1.0")
		(company "Antmicro Ltd")
		(comment 1 "www.antmicro.com")
		(comment 9 "footprints 730-732 of 1170")
	)
	(layers
		(0 "F.Cu" signal)
		(4 "In1.Cu" signal)
		(6 "In2.Cu" signal)
		(8 "In3.Cu" signal)
		(10 "In4.Cu" jumper)
		(12 "In5.Cu" signal)
		(14 "In6.Cu" signal)
		(16 "In7.Cu" signal)
		(18 "In8.Cu" signal)
		(2 "B.Cu" signal)
		(9 "F.Adhes" user "F.Adhesive")
		(11 "B.Adhes" user "B.Adhesive")
		(13 "F.Paste" user)
		(15 "B.Paste" user)
		(5 "F.SilkS" user "F.Silkscreen")
		(7 "B.SilkS" user "B.Silkscreen")
		(1 "F.Mask" user)
		(3 "B.Mask" user)
		(17 "Dwgs.User" user "User.Drawings")
		(19 "Cmts.User" user "User.Comments")
		(21 "Eco1.User" user "User.Eco1")
		(23 "Eco2.User" user "User.Eco2")
		(25 "Edge.Cuts" user)
		(27 "Margin" user)
		(31 "F.CrtYd" user "F.Courtyard")
		(29 "B.CrtYd" user "B.Courtyard")
		(35 "F.Fab" user)
		(33 "B.Fab" user)
	)
	(footprint "antmicro-footprints:USON-10_2.5x1mm_P0.5mm"
		(layer "B.Cu")
		(at 205.796 145.01)
		(descr "USON-10 2.5x1mm_ Pitch 0.5mm")
		(tags "USON-10 2.5x1mm Pitch 0.5mm")
		(property "Reference" "U73"
			(at -3.17 0.89 0)
			(layer "B.SilkS")
			(effects
				(font
					(size 0.7 0.7)
					(thickness 0.15)
				)
				(justify right top mirror)
			)
		)
		(property "Value" "TPD4E05U06QDQARQ1"
			(at 0.018 -2.499 0)
			(layer "B.Fab")
			(effects
				(font
					(size 0.7 0.7)
					(thickness 0.15)
				)
				(justify right top mirror)
			)
		)
		(property "Datasheet" "https://www.ti.com/lit/ds/symlink/tpd4e05u06-q1.pdf?HQS=dis-mous-null-mousermode-dsf-pf-null-wwe&ts=1663591265741&ref_url=https%253A%252F%252Fwww.mouser.com%252F"
			(at 0 0 0)
			(layer "B.Fab")
			(hide yes)
			(effects
				(font
					(size 1.27 1.27)
					(thickness 0.15)
				)
				(justify mirror)
			)
		)
		(property "Description" "TVS diode array, 12 kV, USON-10, 5.5 V, 0.5 pF"
			(at 0 0 0)
			(layer "B.Fab")
			(hide yes)
			(effects
				(font
					(size 1.27 1.27)
					(thickness 0.15)
				)
				(justify mirror)
			)
		)
		(property "Manufacturer" "Texas Instruments"
			(at 0 0 180)
			(unlocked yes)
			(layer "B.Fab")
			(hide yes)
			(effects
				(font
					(size 1 1)
					(thickness 0.15)
				)
				(justify mirror)
			)
		)
		(property "MPN" "TPD4E05U06QDQARQ1"
			(at 0 0 180)
			(unlocked yes)
			(layer "B.Fab")
			(hide yes)
			(effects
				(font
					(size 1 1)
					(thickness 0.15)
				)
				(justify mirror)
			)
		)
		(property "Author" "Antmicro"
			(at 0 0 180)
			(unlocked yes)
			(layer "B.Fab")
			(hide yes)
			(effects
				(font
					(size 1 1)
					(thickness 0.15)
				)
				(justify mirror)
			)
		)
		(property "License" "Apache-2.0"
			(at 0 0 180)
			(unlocked yes)
			(layer "B.Fab")
			(hide yes)
			(effects
				(font
					(size 1 1)
					(thickness 0.15)
				)
				(justify mirror)
			)
		)
		(sheetname "/SFP/")
		(sheetfile "sfp.kicad_sch")
		(attr smd)
		(fp_line
			(start 0.498 -1.398)
			(end -0.5 -1.398)
			(stroke
				(width 0.15)
				(type solid)
			)
			(layer "B.SilkS")
		)
		(fp_line
			(start 0.498 1.401)
			(end -0.5 1.401)
			(stroke
				(width 0.15)
				(type solid)
			)
			(layer "B.SilkS")
		)
		(fp_circle
			(center -0.68 1.27)
			(end -0.63 1.27)
			(stroke
				(width 0.15)
				(type solid)
			)
			(fill yes)
			(layer "B.SilkS")
		)
		(fp_poly
			(pts
				(xy -0.8 1.5) (xy 0.8 1.5) (xy 0.799999 -1.499) (xy -0.799999 -1.499)
			)
			(stroke
				(width 0.05)
				(type solid)
			)
			(fill no)
			(layer "B.CrtYd")
		)
		(fp_line
			(start -0.5 -1.249)
			(end 0.498 -1.249)
			(stroke
				(width 0.15)
				(type solid)
			)
			(layer "B.Fab")
		)
		(fp_line
			(start -0.5 1)
			(end -0.5 -1.249)
			(stroke
				(width 0.15)
				(type solid)
			)
			(layer "B.Fab")
		)
		(fp_line
			(start -0.25 1.25)
			(end -0.5 1)
			(stroke
				(width 0.15)
				(type solid)
			)
			(layer "B.Fab")
		)
		(fp_line
			(start 0.498 1.25)
			(end -0.25 1.25)
			(stroke
				(width 0.15)
				(type solid)
			)
			(layer "B.Fab")
		)
		(fp_line
			(start 0.498 1.25)
			(end 0.498 -1.249)
			(stroke
				(width 0.15)
				(type solid)
			)
			(layer "B.Fab")
		)
		(fp_text user "${REFERENCE}"
			(at -0.802 -4.498 0)
			(layer "B.Fab")
			(effects
				(font
					(size 0.7 0.7)
					(thickness 0.15)
				)
				(justify right top mirror)
			)
		)
		(fp_text user "License: Apache-2.0"
			(at -0.802 -6.9 0)
			(layer "B.Fab")
			(effects
				(font
					(size 0.7 0.7)
					(thickness 0.15)
				)
				(justify right top mirror)
			)
		)
		(fp_text user "Author: Antmicro"
			(at -0.802 -5.7 0)
			(layer "B.Fab")
			(effects
				(font
					(size 0.7 0.7)
					(thickness 0.15)
				)
				(justify right top mirror)
			)
		)
		(pad "1" smd roundrect
			(at -0.387 1 90)
			(size 0.25 0.55)
			(layers "B.Cu" "B.Mask" "B.Paste")
			(roundrect_rratio 0.25)
			(net 824 "/SFP/SDA_SFP")
			(pintype "passive")
		)
		(pad "2" smd roundrect
			(at -0.387 0.5 90)
			(size 0.25 0.55)
			(layers "B.Cu" "B.Mask" "B.Paste")
			(roundrect_rratio 0.25)
			(net 823 "/SFP/SCL_SFP")
			(pintype "passive")
		)
		(pad "3" smd roundrect
			(at -0.387 0 90)
			(size 0.4 0.55)
			(layers "B.Cu" "B.Mask" "B.Paste")
			(roundrect_rratio 0.25)
			(net 1 "GND")
			(pintype "power_in")
		)
		(pad "4" smd roundrect
			(at -0.387 -0.498 90)
			(size 0.25 0.55)
			(layers "B.Cu" "B.Mask" "B.Paste")
			(roundrect_rratio 0.25)
			(net 1296 "/SFP/SFP_MOD_ABS")
			(pintype "passive")
		)
		(pad "5" smd roundrect
			(at -0.387 -0.998 90)
			(size 0.25 0.55)
			(layers "B.Cu" "B.Mask" "B.Paste")
			(roundrect_rratio 0.25)
			(net 1 "GND")
			(pintype "passive")
		)
		(pad "6" smd roundrect
			(at 0.385001 -0.998 90)
			(size 0.25 0.55)
			(layers "B.Cu" "B.Mask" "B.Paste")
			(roundrect_rratio 0.25)
			(net 1 "GND")
			(pintype "passive")
		)
		(pad "7" smd roundrect
			(at 0.385 -0.498 90)
			(size 0.25 0.55)
			(layers "B.Cu" "B.Mask" "B.Paste")
			(roundrect_rratio 0.25)
			(net 1296 "/SFP/SFP_MOD_ABS")
			(pintype "passive")
		)
		(pad "8" smd roundrect
			(at 0.385 0 90)
			(size 0.4 0.55)
			(layers "B.Cu" "B.Mask" "B.Paste")
			(roundrect_rratio 0.25)
			(net 1 "GND")
			(pintype "passive")
		)
		(pad "9" smd roundrect
			(at 0.385001 0.5 90)
			(size 0.25 0.55)
			(layers "B.Cu" "B.Mask" "B.Paste")
			(roundrect_rratio 0.25)
			(net 823 "/SFP/SCL_SFP")
			(pintype "passive")
		)
		(pad "10" smd roundrect
			(at 0.385 1 90)
			(size 0.25 0.55)
			(layers "B.Cu" "B.Mask" "B.Paste")
			(roundrect_rratio 0.25)
			(net 824 "/SFP/SDA_SFP")
			(pintype "passive")
		)
	)
	(footprint "antmicro-footprints:C_0402_1005Metric"
		(layer "B.Cu")
		(at 117.89 70.6)
		(descr "Capacitor SMD 0402")
		(tags "capacitor SMD 0402")
		(property "Reference" "C15"
			(at -0.69 0.7 0)
			(layer "B.SilkS")
			(effects
				(font
					(size 0.7 0.7)
					(thickness 0.15)
				)
				(justify right top mirror)
			)
		)
		(property "Value" "C_10u_0402"
			(at -1.022927 -2.155213 0)
			(layer "B.Fab")
			(effects
				(font
					(size 0.7 0.7)
					(thickness 0.15)
				)
				(justify right top mirror)
			)
		)
		(property "Datasheet" "https://www.yageo.com/en/Chart/Download/pdf/CC0402MRX5R5BB106"
			(at 0 0 0)
			(layer "B.Fab")
			(hide yes)
			(effects
				(font
					(size 1.27 1.27)
					(thickness 0.15)
				)
				(justify mirror)
			)
		)
		(property "Description" "SMD Multilayer Ceramic Capacitor, 10 µF, 6.3 V, 0402 [1005 Metric], ± 20%, X5R, CC Series"
			(at 0 0 0)
			(layer "B.Fab")
			(hide yes)
			(effects
				(font
					(size 1.27 1.27)
					(thickness 0.15)
				)
				(justify mirror)
			)
		)
		(property "MPN" "CC0402MRX5R5BB106"
			(at 0 0 0)
			(unlocked yes)
			(layer "B.Fab")
			(hide yes)
			(effects
				(font
					(size 1 1)
					(thickness 0.15)
				)
				(justify mirror)
			)
		)
		(property "Manufacturer" "YAGEO"
			(at 0 0 0)
			(unlocked yes)
			(layer "B.Fab")
			(hide yes)
			(effects
				(font
					(size 1 1)
					(thickness 0.15)
				)
				(justify mirror)
			)
		)
		(property "License" "Apache-2.0"
			(at 0 0 0)
			(unlocked yes)
			(layer "B.Fab")
			(hide yes)
			(effects
				(font
					(size 1 1)
					(thickness 0.15)
				)
				(justify mirror)
			)
		)
		(property "Author" "Antmicro"
			(at 0 0 0)
			(unlocked yes)
			(layer "B.Fab")
			(hide yes)
			(effects
				(font
					(size 1 1)
					(thickness 0.15)
				)
				(justify mirror)
			)
		)
		(property "Val" "10u"
			(at 0 0 0)
			(unlocked yes)
			(layer "B.Fab")
			(hide yes)
			(effects
				(font
					(size 1 1)
					(thickness 0.15)
				)
				(justify mirror)
			)
		)
		(property "Voltage" ""
			(at 0 0 0)
			(unlocked yes)
			(layer "B.Fab")
			(hide yes)
			(effects
				(font
					(size 1 1)
					(thickness 0.15)
				)
				(justify mirror)
			)
		)
		(property "Dielectric" "template_dielectric"
			(at 0 0 0)
			(unlocked yes)
			(layer "B.Fab")
			(hide yes)
			(effects
				(font
					(size 1 1)
					(thickness 0.15)
				)
				(justify mirror)
			)
		)
		(sheetname "/SoM_Power/")
		(sheetfile "som_power.kicad_sch")
		(attr smd)
		(fp_rect
			(start -0.925 0.47)
			(end 0.925 -0.47)
			(stroke
				(width 0.05)
				(type default)
			)
			(fill no)
			(layer "B.CrtYd")
		)
		(fp_line
			(start -0.494 -0.248)
			(end -0.494 0.25)
			(stroke
				(width 0.15)
				(type solid)
			)
			(layer "B.Fab")
		)
		(fp_line
			(start -0.494 0.25)
			(end 0.504 0.25)
			(stroke
				(width 0.15)
				(type solid)
			)
			(layer "B.Fab")
		)
		(fp_line
			(start 0.504 -0.248)
			(end -0.494 -0.248)
			(stroke
				(width 0.15)
				(type solid)
			)
			(layer "B.Fab")
		)
		(fp_line
			(start 0.504 0.25)
			(end 0.504 -0.248)
			(stroke
				(width 0.15)
				(type solid)
			)
			(layer "B.Fab")
		)
		(fp_text user "License: Apache-2.0"
			(at -0.939 -5.799 0)
			(layer "B.Fab")
			(effects
				(font
					(size 0.7 0.7)
					(thickness 0.15)
				)
				(justify right top mirror)
			)
		)
		(fp_text user "${REFERENCE}"
			(at -0.939 -4.599 0)
			(layer "B.Fab")
			(effects
				(font
					(size 0.7 0.7)
					(thickness 0.15)
				)
				(justify right top mirror)
			)
		)
		(fp_text user "Author: Antmicro"
			(at -0.939 -3.399 0)
			(layer "B.Fab")
			(effects
				(font
					(size 0.7 0.7)
					(thickness 0.15)
				)
				(justify right top mirror)
			)
		)
		(pad "1" smd roundrect
			(at -0.48 0)
			(size 0.59 0.64)
			(layers "B.Cu" "B.Mask" "B.Paste")
			(roundrect_rratio 0.25)
			(net 1 "GND")
			(pintype "passive")
		)
		(pad "2" smd roundrect
			(at 0.48 0)
			(size 0.59 0.64)
			(layers "B.Cu" "B.Mask" "B.Paste")
			(roundrect_rratio 0.25)
			(net 213 "+5V_SOM")
			(pintype "passive")
		)
	)
	(footprint "antmicro-footprints:R_0402_1005Metric"
		(layer "B.Cu")
		(at 208.726 143)
		(descr "Resistor SMD 0402")
		(tags "resistor SMD 0402")
		(property "Reference" "R188"
			(at 1 -0.3 0)
			(layer "B.SilkS")
			(effects
				(font
					(size 0.7 0.7)
					(thickness 0.15)
				)
				(justify right top mirror)
			)
		)
		(property "Value" "R_1k_0402"
			(at -1.011843 -1.772047 0)
			(layer "B.Fab")
			(effects
				(font
					(size 0.7 0.7)
					(thickness 0.15)
				)
				(justify right top mirror)
			)
		)
		(property "Datasheet" "https://www.bourns.com/docs/product-datasheets/cr.pdf"
			(at 0 0 0)
			(layer "B.Fab")
			(hide yes)
			(effects
				(font
					(size 1.27 1.27)
					(thickness 0.15)
				)
				(justify mirror)
			)
		)
		(property "Description" "SMD Chip Resistor, 1 kohm, ± 1%, 63 mW, 0402 [1005 Metric], Thick Film, General Purpose"
			(at 0 0 0)
			(layer "B.Fab")
			(hide yes)
			(effects
				(font
					(size 1.27 1.27)
					(thickness 0.15)
				)
				(justify mirror)
			)
		)
		(property "MPN" "CR0402-FX-1001GLF"
			(at 0 0 180)
			(unlocked yes)
			(layer "B.Fab")
			(hide yes)
			(effects
				(font
					(size 1 1)
					(thickness 0.15)
				)
				(justify mirror)
			)
		)
		(property "Manufacturer" "Bourns"
			(at 0 0 180)
			(unlocked yes)
			(layer "B.Fab")
			(hide yes)
			(effects
				(font
					(size 1 1)
					(thickness 0.15)
				)
				(justify mirror)
			)
		)
		(property "License" "Apache-2.0"
			(at 0 0 180)
			(unlocked yes)
			(layer "B.Fab")
			(hide yes)
			(effects
				(font
					(size 1 1)
					(thickness 0.15)
				)
				(justify mirror)
			)
		)
		(property "Author" "Antmicro"
			(at 0 0 180)
			(unlocked yes)
			(layer "B.Fab")
			(hide yes)
			(effects
				(font
					(size 1 1)
					(thickness 0.15)
				)
				(justify mirror)
			)
		)
		(property "Val" "1k"
			(at 0 0 180)
			(unlocked yes)
			(layer "B.Fab")
			(hide yes)
			(effects
				(font
					(size 1 1)
					(thickness 0.15)
				)
				(justify mirror)
			)
		)
		(property "Tolerance" "1%"
			(at 0 0 180)
			(unlocked yes)
			(layer "B.Fab")
			(hide yes)
			(effects
				(font
					(size 1 1)
					(thickness 0.15)
				)
				(justify mirror)
			)
		)
		(sheetname "/SFP/")
		(sheetfile "sfp.kicad_sch")
		(attr smd)
		(fp_rect
			(start -0.925 0.47)
			(end 0.925 -0.47)
			(stroke
				(width 0.05)
				(type default)
			)
			(fill no)
			(layer "B.CrtYd")
		)
		(fp_rect
			(start -0.5 0.25)
			(end 0.5 -0.25)
			(stroke
				(width 0.15)
				(type solid)
			)
			(fill no)
			(layer "B.Fab")
		)
		(fp_text user "${REFERENCE}"
			(at -0.95 -3.168 0)
			(layer "B.Fab")
			(effects
				(font
					(size 0.7 0.7)
					(thickness 0.15)
				)
				(justify right top mirror)
			)
		)
		(fp_text user "Author: Antmicro"
			(at -0.95 -4.169 0)
			(layer "B.Fab")
			(effects
				(font
					(size 0.7 0.7)
					(thickness 0.15)
				)
				(justify right top mirror)
			)
		)
		(fp_text user "License: Apache-2.0"
			(at -0.95 -5.169 0)
			(layer "B.Fab")
			(effects
				(font
					(size 0.7 0.7)
					(thickness 0.15)
				)
				(justify right top mirror)
			)
		)
		(pad "1" smd roundrect
			(at -0.48 0)
			(size 0.59 0.64)
			(layers "B.Cu" "B.Mask" "B.Paste")
			(roundrect_rratio 0.25)
			(net 1368 "Net-(J12-RS0)")
			(pintype "passive")
		)
		(pad "2" smd roundrect
			(at 0.48 0)
			(size 0.59 0.64)
			(layers "B.Cu" "B.Mask" "B.Paste")
			(roundrect_rratio 0.25)
			(net 2 "+3V3")
			(pintype "passive")
		)
	)
)
